(kicad_pcb
	(version 20240108)
	(generator "pcbnew")
	(generator_version "8.0")
	(general
		(thickness 1.6)
		(legacy_teardrops no)
	)
	(paper "A4")
	(title_block
		(title "Jetson Orin Baseboard OCuLink Expansion")
		(date "2025-03-18")
		(rev "1.1.0")
		(company "Antmicro Ltd")
		(comment 1 "www.antmicro.com")
		(comment 9 "footprints 54-54 of 119")
	)
	(layers
		(0 "F.Cu" signal)
		(1 "In1.Cu" signal)
		(2 "In2.Cu" signal)
		(31 "B.Cu" signal)
		(32 "B.Adhes" user "B.Adhesive")
		(33 "F.Adhes" user "F.Adhesive")
		(34 "B.Paste" user)
		(35 "F.Paste" user)
		(36 "B.SilkS" user "B.Silkscreen")
		(37 "F.SilkS" user "F.Silkscreen")
		(38 "B.Mask" user)
		(39 "F.Mask" user)
		(40 "Dwgs.User" user "User.Drawings")
		(41 "Cmts.User" user "User.Comments")
		(42 "Eco1.User" user "User.Eco1")
		(43 "Eco2.User" user "User.Eco2")
		(44 "Edge.Cuts" user)
		(45 "Margin" user)
		(46 "B.CrtYd" user "B.Courtyard")
		(47 "F.CrtYd" user "F.Courtyard")
		(48 "B.Fab" user)
		(49 "F.Fab" user)
	)
	(footprint "antmicro-footprints:WQFN-42-1EP_3.5x9mm_P0.5mm"
		(layer "F.Cu")
		(at 125.005 115.628251 90)
		(descr "WQFN, 42 Pin (http://www.ti.com/lit/ds/symlink/ts3l501e.pdf#page=23), generated with kicad-footprint-generator ipc_noLead_generator.py")
		(tags "WQFN NoLead")
		(property "Reference" "U2"
			(at 0.868251 -4.985 90)
			(layer "F.SilkS")
			(effects
				(font
					(size 0.7 0.7)
					(thickness 0.15)
				)
				(justify left bottom)
			)
		)
		(property "Value" "PI3EQX16904GL"
			(at 0 5.82 90)
			(layer "F.Fab")
			(effects
				(font
					(size 0.7 0.7)
					(thickness 0.15)
				)
				(justify left bottom)
			)
		)
		(property "Footprint" "antmicro-footprints:WQFN-42-1EP_3.5x9mm_P0.5mm"
			(at 0 0 90)
			(layer "F.Fab")
			(hide yes)
			(effects
				(font
					(size 1.27 1.27)
					(thickness 0.15)
				)
			)
		)
		(property "Datasheet" "https://www.diodes.com/part/view/PI3EQX16904GL"
			(at 0 0 90)
			(layer "F.Fab")
			(hide yes)
			(effects
				(font
					(size 1.27 1.27)
					(thickness 0.15)
				)
			)
		)
		(property "Description" "16Gbps 4-Channel ReDriver with Linear Equalization"
			(at 0 0 90)
			(layer "F.Fab")
			(hide yes)
			(effects
				(font
					(size 1.27 1.27)
					(thickness 0.15)
				)
			)
		)
		(property "MPN" "PI3EQX16904GLZHEX"
			(at 0 0 90)
			(unlocked yes)
			(layer "F.Fab")
			(hide yes)
			(effects
				(font
					(size 1 1)
					(thickness 0.15)
				)
			)
		)
		(property "Manufacturer" "Diodes Incorporated"
			(at 0 0 90)
			(unlocked yes)
			(layer "F.Fab")
			(hide yes)
			(effects
				(font
					(size 1 1)
					(thickness 0.15)
				)
			)
		)
		(property "Author" "Antmicro"
			(at 0 0 90)
			(unlocked yes)
			(layer "F.Fab")
			(hide yes)
			(effects
				(font
					(size 1 1)
					(thickness 0.15)
				)
			)
		)
		(property "License" "Apache-2.0"
			(at 0 0 90)
			(unlocked yes)
			(layer "F.Fab")
			(hide yes)
			(effects
				(font
					(size 1 1)
					(thickness 0.15)
				)
			)
		)
		(sheetname "Root")
		(sheetfile "jetson-orin-baseboard-oculink-expansion.kicad_sch")
		(attr smd)
		(fp_line
			(start 1.86 -4.611)
			(end 1.86 -4.385)
			(stroke
				(width 0.15)
				(type solid)
			)
			(layer "F.SilkS")
		)
		(fp_line
			(start 1.134 -4.611)
			(end 1.86 -4.611)
			(stroke
				(width 0.15)
				(type solid)
			)
			(layer "F.SilkS")
		)
		(fp_line
			(start -1.135 -4.611)
			(end -1.861 -4.611)
			(stroke
				(width 0.15)
				(type solid)
			)
			(layer "F.SilkS")
		)
		(fp_line
			(start 1.86 4.61)
			(end 1.86 4.384)
			(stroke
				(width 0.15)
				(type solid)
			)
			(layer "F.SilkS")
		)
		(fp_line
			(start 1.134 4.61)
			(end 1.86 4.61)
			(stroke
				(width 0.15)
				(type solid)
			)
			(layer "F.SilkS")
		)
		(fp_line
			(start -1.135 4.61)
			(end -1.861 4.61)
			(stroke
				(width 0.15)
				(type solid)
			)
			(layer "F.SilkS")
		)
		(fp_line
			(start -1.861 4.61)
			(end -1.861 4.384)
			(stroke
				(width 0.15)
				(type solid)
			)
			(layer "F.SilkS")
		)
		(fp_circle
			(center -2.68 -4)
			(end -2.63 -4)
			(stroke
				(width 0.15)
				(type solid)
			)
			(fill solid)
			(layer "F.SilkS")
		)
		(fp_rect
			(start -2.25 -5)
			(end 2.249 4.998)
			(stroke
				(width 0.05)
				(type solid)
			)
			(fill none)
			(layer "F.CrtYd")
		)
		(fp_line
			(start 1.749 -4.5)
			(end 1.749 4.498)
			(stroke
				(width 0.15)
				(type solid)
			)
			(layer "F.Fab")
		)
		(fp_line
			(start -0.875 -4.5)
			(end 1.749 -4.5)
			(stroke
				(width 0.15)
				(type solid)
			)
			(layer "F.Fab")
		)
		(fp_line
			(start -1.75 -3.625)
			(end -0.875 -4.5)
			(stroke
				(width 0.15)
				(type solid)
			)
			(layer "F.Fab")
		)
		(fp_line
			(start 1.749 4.498)
			(end -1.75 4.498)
			(stroke
				(width 0.15)
				(type solid)
			)
			(layer "F.Fab")
		)
		(fp_line
			(start -1.75 4.498)
			(end -1.75 -3.625)
			(stroke
				(width 0.15)
				(type solid)
			)
			(layer "F.Fab")
		)
		(fp_text user "License: Apache-2.0"
			(at -2.73 9.02 90)
			(layer "F.Fab")
			(hide yes)
			(effects
				(font
					(size 0.7 0.7)
					(thickness 0.15)
				)
				(justify left bottom)
			)
		)
		(fp_text user "${REFERENCE}"
			(at -2.73 10.22 90)
			(layer "F.Fab")
			(hide yes)
			(effects
				(font
					(size 0.7 0.7)
					(thickness 0.15)
				)
				(justify left bottom)
			)
		)
		(fp_text user "Author: Antmicro"
			(at -2.73 7.82 90)
			(layer "F.Fab")
			(hide yes)
			(effects
				(font
					(size 0.7 0.7)
					(thickness 0.15)
				)
				(justify left bottom)
			)
		)
		(pad "" smd roundrect
			(at -0.51 -3.242 90)
			(size 0.83 0.87)
			(layers "F.Paste")
			(roundrect_rratio 0.25)
		)
		(pad "" smd roundrect
			(at -0.51 -2.161 90)
			(size 0.83 0.87)
			(layers "F.Paste")
			(roundrect_rratio 0.25)
		)
		(pad "" smd roundrect
			(at -0.51 -1.081 90)
			(size 0.83 0.87)
			(layers "F.Paste")
			(roundrect_rratio 0.25)
		)
		(pad "" smd roundrect
			(at -0.51 0 90)
			(size 0.83 0.87)
			(layers "F.Paste")
			(roundrect_rratio 0.25)
		)
		(pad "" smd roundrect
			(at -0.51 1.08 90)
			(size 0.83 0.87)
			(layers "F.Paste")
			(roundrect_rratio 0.25)
		)
		(pad "" smd roundrect
			(at -0.51 2.16 90)
			(size 0.83 0.87)
			(layers "F.Paste")
			(roundrect_rratio 0.25)
		)
		(pad "" smd roundrect
			(at -0.51 3.24 90)
			(size 0.83 0.87)
			(layers "F.Paste")
			(roundrect_rratio 0.25)
		)
		(pad "" smd roundrect
			(at 0.508 -3.242 90)
			(size 0.83 0.87)
			(layers "F.Paste")
			(roundrect_rratio 0.25)
		)
		(pad "" smd roundrect
			(at 0.508 -2.161 90)
			(size 0.83 0.87)
			(layers "F.Paste")
			(roundrect_rratio 0.25)
		)
		(pad "" smd roundrect
			(at 0.508 -1.081 90)
			(size 0.83 0.87)
			(layers "F.Paste")
			(roundrect_rratio 0.25)
		)
		(pad "" smd roundrect
			(at 0.508 0 90)
			(size 0.83 0.87)
			(layers "F.Paste")
			(roundrect_rratio 0.25)
		)
		(pad "" smd roundrect
			(at 0.508 1.08 90)
			(size 0.83 0.87)
			(layers "F.Paste")
			(roundrect_rratio 0.25)
		)
		(pad "" smd roundrect
			(at 0.508 2.16 90)
			(size 0.83 0.87)
			(layers "F.Paste")
			(roundrect_rratio 0.25)
		)
		(pad "" smd roundrect
			(at 0.508 3.24 90)
			(size 0.83 0.87)
			(layers "F.Paste")
			(roundrect_rratio 0.25)
		)
		(pad "1" smd roundrect
			(at -1.688 -4 90)
			(size 0.875 0.25)
			(layers "F.Cu" "F.Paste" "F.Mask")
			(roundrect_rratio 0.25)
			(net 91 "/RX_EQ2")
			(pinfunction "EQ2")
			(pintype "passive")
		)
		(pad "2" smd roundrect
			(at -1.688 -3.5 90)
			(size 0.875 0.25)
			(layers "F.Cu" "F.Paste" "F.Mask")
			(roundrect_rratio 0.25)
			(net 94 "/RX_SW")
			(pinfunction "SW1")
			(pintype "input")
		)
		(pad "3" smd roundrect
			(at -1.688 -3 90)
			(size 0.875 0.25)
			(layers "F.Cu" "F.Paste" "F.Mask")
			(roundrect_rratio 0.25)
			(net 23 "+3V3")
			(pinfunction "VCC")
			(pintype "passive")
		)
		(pad "4" smd roundrect
			(at -1.688 -2.5 90)
			(size 0.875 0.25)
			(layers "F.Cu" "F.Paste" "F.Mask")
			(roundrect_rratio 0.25)
			(net 84 "/PCIE_{O}_RX1-")
			(pinfunction "A0RX+")
			(pintype "input")
		)
		(pad "5" smd roundrect
			(at -1.688 -2 90)
			(size 0.875 0.25)
			(layers "F.Cu" "F.Paste" "F.Mask")
			(roundrect_rratio 0.25)
			(net 82 "/PCIE_{O}_RX1+")
			(pinfunction "A0RX-")
			(pintype "input")
		)
		(pad "6" smd roundrect
			(at -1.688 -1.5 90)
			(size 0.875 0.25)
			(layers "F.Cu" "F.Paste" "F.Mask")
			(roundrect_rratio 0.25)
			(net 23 "+3V3")
			(pinfunction "VCC")
			(pintype "passive")
		)
		(pad "7" smd roundrect
			(at -1.688 -1 90)
			(size 0.875 0.25)
			(layers "F.Cu" "F.Paste" "F.Mask")
			(roundrect_rratio 0.25)
			(net 83 "/PCIE_{O}_RX0-")
			(pinfunction "A1RX+")
			(pintype "input")
		)
		(pad "8" smd roundrect
			(at -1.688 -0.5 90)
			(size 0.875 0.25)
			(layers "F.Cu" "F.Paste" "F.Mask")
			(roundrect_rratio 0.25)
			(net 81 "/PCIE_{O}_RX0+")
			(pinfunction "A1RX-")
			(pintype "input")
		)
		(pad "9" smd roundrect
			(at -1.688 0 90)
			(size 0.875 0.25)
			(layers "F.Cu" "F.Paste" "F.Mask")
			(roundrect_rratio 0.25)
			(net 23 "+3V3")
			(pinfunction "VCC")
			(pintype "passive")
		)
		(pad "10" smd roundrect
			(at -1.688 0.5 90)
			(size 0.875 0.25)
			(layers "F.Cu" "F.Paste" "F.Mask")
			(roundrect_rratio 0.25)
			(net 118 "unconnected-(U2-A2RX+-Pad10)")
			(pinfunction "A2RX+")
			(pintype "input+no_connect")
		)
		(pad "11" smd roundrect
			(at -1.688 1 90)
			(size 0.875 0.25)
			(layers "F.Cu" "F.Paste" "F.Mask")
			(roundrect_rratio 0.25)
			(net 113 "unconnected-(U2-A2RX--Pad11)")
			(pinfunction "A2RX-")
			(pintype "input+no_connect")
		)
		(pad "12" smd roundrect
			(at -1.688 1.5 90)
			(size 0.875 0.25)
			(layers "F.Cu" "F.Paste" "F.Mask")
			(roundrect_rratio 0.25)
			(net 23 "+3V3")
			(pinfunction "VCC")
			(pintype "power_in")
		)
		(pad "13" smd roundrect
			(at -1.688 2 90)
			(size 0.875 0.25)
			(layers "F.Cu" "F.Paste" "F.Mask")
			(roundrect_rratio 0.25)
			(net 127 "unconnected-(U2-A3RX+-Pad13)")
			(pinfunction "A3RX+")
			(pintype "input+no_connect")
		)
		(pad "14" smd roundrect
			(at -1.688 2.5 90)
			(size 0.875 0.25)
			(layers "F.Cu" "F.Paste" "F.Mask")
			(roundrect_rratio 0.25)
			(net 114 "unconnected-(U2-A3RX--Pad14)")
			(pinfunction "A3RX-")
			(pintype "input+no_connect")
		)
		(pad "15" smd roundrect
			(at -1.688 3 90)
			(size 0.875 0.25)
			(layers "F.Cu" "F.Paste" "F.Mask")
			(roundrect_rratio 0.25)
			(net 23 "+3V3")
			(pinfunction "VCC")
			(pintype "passive")
		)
		(pad "16" smd roundrect
			(at -1.688 3.5 90)
			(size 0.875 0.25)
			(layers "F.Cu" "F.Paste" "F.Mask")
			(roundrect_rratio 0.25)
			(net 110 "Net-(U2-~{I2C_{RESET}})")
			(pinfunction "~{I2C_{RESET}}")
			(pintype "input")
		)
		(pad "17" smd roundrect
			(at -1.688 4 90)
			(size 0.875 0.25)
			(layers "F.Cu" "F.Paste" "F.Mask")
			(roundrect_rratio 0.25)
			(net 51 "GND")
			(pinfunction "AD1")
			(pintype "passive")
		)
		(pad "18" smd roundrect
			(at -0.75 4.437 90)
			(size 0.25 0.875)
			(layers "F.Cu" "F.Paste" "F.Mask")
			(roundrect_rratio 0.25)
			(net 95 "Net-(U2-SDA)")
			(pinfunction "SDA")
			(pintype "open_collector")
		)
		(pad "19" smd roundrect
			(at -0.25 4.437 90)
			(size 0.25 0.875)
			(layers "F.Cu" "F.Paste" "F.Mask")
			(roundrect_rratio 0.25)
			(net 106 "Net-(U2-SCL)")
			(pinfunction "SCL")
			(pintype "open_collector")
		)
		(pad "20" smd roundrect
			(at 0.25 4.437 90)
			(size 0.25 0.875)
			(layers "F.Cu" "F.Paste" "F.Mask")
			(roundrect_rratio 0.25)
			(net 71 "/~{CPRSNT}")
			(pinfunction "~{PRSNT}")
			(pintype "input")
		)
		(pad "21" smd roundrect
			(at 0.75 4.437 90)
			(size 0.25 0.875)
			(layers "F.Cu" "F.Paste" "F.Mask")
			(roundrect_rratio 0.25)
			(net 103 "Net-(U2-EN_{I2C})")
			(pinfunction "EN_{I2C}")
			(pintype "input")
		)
		(pad "22" smd roundrect
			(at 1.687 4 90)
			(size 0.875 0.25)
			(layers "F.Cu" "F.Paste" "F.Mask")
			(roundrect_rratio 0.25)
			(net 109 "Net-(U2-I2C_{DONE})")
			(pinfunction "I2C_{DONE}")
			(pintype "input")
		)
		(pad "23" smd roundrect
			(at 1.687 3.5 90)
			(size 0.875 0.25)
			(layers "F.Cu" "F.Paste" "F.Mask")
			(roundrect_rratio 0.25)
			(net 97 "Net-(U2-RXDET)")
			(pinfunction "RXDET")
			(pintype "input")
		)
		(pad "24" smd roundrect
			(at 1.687 3 90)
			(size 0.875 0.25)
			(layers "F.Cu" "F.Paste" "F.Mask")
			(roundrect_rratio 0.25)
			(net 23 "+3V3")
			(pinfunction "VCC")
			(pintype "passive")
		)
		(pad "25" smd roundrect
			(at 1.687 2.5 90)
			(size 0.875 0.25)
			(layers "F.Cu" "F.Paste" "F.Mask")
			(roundrect_rratio 0.25)
			(net 115 "unconnected-(U2-A3TX--Pad25)")
			(pinfunction "A3TX-")
			(pintype "output+no_connect")
		)
		(pad "26" smd roundrect
			(at 1.687 2 90)
			(size 0.875 0.25)
			(layers "F.Cu" "F.Paste" "F.Mask")
			(roundrect_rratio 0.25)
			(net 128 "unconnected-(U2-A3TX+-Pad26)")
			(pinfunction "A3TX+")
			(pintype "input+no_connect")
		)
		(pad "27" smd roundrect
			(at 1.687 1.5 90)
			(size 0.875 0.25)
			(layers "F.Cu" "F.Paste" "F.Mask")
			(roundrect_rratio 0.25)
			(net 23 "+3V3")
			(pinfunction "VCC")
			(pintype "passive")
		)
		(pad "28" smd roundrect
			(at 1.687 1 90)
			(size 0.875 0.25)
			(layers "F.Cu" "F.Paste" "F.Mask")
			(roundrect_rratio 0.25)
			(net 117 "unconnected-(U2-A2TX--Pad28)")
			(pinfunction "A2TX-")
			(pintype "output+no_connect")
		)
		(pad "29" smd roundrect
			(at 1.687 0.5 90)
			(size 0.875 0.25)
			(layers "F.Cu" "F.Paste" "F.Mask")
			(roundrect_rratio 0.25)
			(net 116 "unconnected-(U2-A2TX+-Pad29)")
			(pinfunction "A2TX+")
			(pintype "input+no_connect")
		)
		(pad "30" smd roundrect
			(at 1.687 0 90)
			(size 0.875 0.25)
			(layers "F.Cu" "F.Paste" "F.Mask")
			(roundrect_rratio 0.25)
			(net 23 "+3V3")
			(pinfunction "VCC")
			(pintype "passive")
		)
		(pad "31" smd roundrect
			(at 1.687 -0.5 90)
			(size 0.875 0.25)
			(layers "F.Cu" "F.Paste" "F.Mask")
			(roundrect_rratio 0.25)
			(net 77 "/PCIE_{I}_C.RX0+")
			(pinfunction "A1TX-")
			(pintype "output")
		)
		(pad "32" smd roundrect
			(at 1.687 -1 90)
			(size 0.875 0.25)
			(layers "F.Cu" "F.Paste" "F.Mask")
			(roundrect_rratio 0.25)
			(net 73 "/PCIE_{I}_C.RX0-")
			(pinfunction "A1TX+")
			(pintype "input")
		)
		(pad "33" smd roundrect
			(at 1.687 -1.5 90)
			(size 0.875 0.25)
			(layers "F.Cu" "F.Paste" "F.Mask")
			(roundrect_rratio 0.25)
			(net 23 "+3V3")
			(pinfunction "VCC")
			(pintype "passive")
		)
		(pad "34" smd roundrect
			(at 1.687 -2 90)
			(size 0.875 0.25)
			(layers "F.Cu" "F.Paste" "F.Mask")
			(roundrect_rratio 0.25)
			(net 80 "/PCIE_{I}_C.RX1+")
			(pinfunction "A0TX-")
			(pintype "output")
		)
		(pad "35" smd roundrect
			(at 1.687 -2.5 90)
			(size 0.875 0.25)
			(layers "F.Cu" "F.Paste" "F.Mask")
			(roundrect_rratio 0.25)
			(net 76 "/PCIE_{I}_C.RX1-")
			(pinfunction "A0TX+")
			(pintype "input")
		)
		(pad "36" smd roundrect
			(at 1.687 -3 90)
			(size 0.875 0.25)
			(layers "F.Cu" "F.Paste" "F.Mask")
			(roundrect_rratio 0.25)
			(net 23 "+3V3")
			(pinfunction "VCC")
			(pintype "passive")
		)
		(pad "37" smd roundrect
			(at 1.687 -3.5 90)
			(size 0.875 0.25)
			(layers "F.Cu" "F.Paste" "F.Mask")
			(roundrect_rratio 0.25)
			(net 92 "/RX_FG0")
			(pinfunction "FG0")
			(pintype "passive")
		)
		(pad "38" smd roundrect
			(at 1.687 -4 90)
			(size 0.875 0.25)
			(layers "F.Cu" "F.Paste" "F.Mask")
			(roundrect_rratio 0.25)
			(net 93 "/RX_FG1")
			(pinfunction "FG1")
			(pintype "passive")
		)
		(pad "39" smd roundrect
			(at 0.75 -4.438 90)
			(size 0.25 0.875)
			(layers "F.Cu" "F.Paste" "F.Mask")
			(roundrect_rratio 0.25)
			(net 89 "/RX_EQ0")
			(pinfunction "EQ0")
			(pintype "passive")
		)
		(pad "40" smd roundrect
			(at 0.25 -4.438 90)
			(size 0.25 0.875)
			(layers "F.Cu" "F.Paste" "F.Mask")
			(roundrect_rratio 0.25)
			(net 90 "/RX_EQ1")
			(pinfunction "EQ1")
			(pintype "passive")
		)
		(pad "41" smd roundrect
			(at -0.25 -4.438 90)
			(size 0.25 0.875)
			(layers "F.Cu" "F.Paste" "F.Mask")
			(roundrect_rratio 0.25)
			(net 51 "GND")
			(pinfunction "AD2")
			(pintype "passive")
		)
		(pad "42" smd roundrect
			(at -0.75 -4.438 90)
			(size 0.25 0.875)
			(layers "F.Cu" "F.Paste" "F.Mask")
			(roundrect_rratio 0.25)
			(net 51 "GND")
			(pinfunction "AD3")
			(pintype "passive")
		)
		(pad "43" smd rect
			(at 0 0 90)
			(size 2.05 7.55)
			(layers "F.Cu" "F.Mask")
			(net 51 "GND")
			(pinfunction "GND")
			(pintype "power_in")
		)
	)
)
